# BASEBOARD_FAB2 (Tioga Pass) — schematic netlist excerpt (pin names and nets, part order shuffled) for the footprints in the layout excerpt that follows; sources: Cadence DE-HDL packaged netlist, KiCad conversion of Wiwynn_Tioga_Pass_MB.brd

R6W4  RES  4.75K 1% CHIP  pkg 0402  page 247 : A = P3V3_STBY ; B = PCA9555_A2
C2T8  CAP_A  0.1UF 16V 10% X7R  pkg 0402V  page 154 : A = P3V3_STBY ; B = GND
C25W54  CAP  1.0UF 16V 10% X6S  pkg 0402  page 149 : A = P1V2_AUX_BMC ; B = GND

(kicad_pcb
	(version 20260206)
	(generator "pcbnew")
	(generator_version "10.0")
	(general
		(thickness 1.6)
		(legacy_teardrops no)
	)
	(paper "A4")
	(title_block
		(title "Wiwynn_Tioga_Pass_MB.brd")
		(comment 1 "Tioga Pass / footprints 3397-3399 of 4770")
	)
	(layers
		(0 "F.Cu" signal "TOP")
		(4 "In1.Cu" signal "L2GND")
		(6 "In2.Cu" signal "L3")
		(8 "In3.Cu" signal "L4GND")
		(10 "In4.Cu" signal "L5")
		(12 "In5.Cu" signal "L6GND")
		(14 "In6.Cu" signal "L7VCC")
		(16 "In7.Cu" signal "L8VCC")
		(18 "In8.Cu" signal "L9GND")
		(20 "In9.Cu" signal "L10")
		(22 "In10.Cu" signal "L11GND")
		(24 "In11.Cu" signal "L12")
		(26 "In12.Cu" signal "L13GND")
		(2 "B.Cu" signal "BOTTOM")
		(9 "F.Adhes" user "F.Adhesive")
		(11 "B.Adhes" user "B.Adhesive")
		(13 "F.Paste" user "Package Geometry/Pastemask Top")
		(15 "B.Paste" user "Package Geometry/Pastemask Bottom")
		(5 "F.SilkS" user "Ref Des/Silkscreen Top")
		(7 "B.SilkS" user "Ref Des/Silkscreen Bottom")
		(1 "F.Mask" user "Board Geometry/Soldermask Top")
		(3 "B.Mask" user "Board Geometry/Soldermask Bottom")
		(17 "Dwgs.User" user "User.Drawings")
		(19 "Cmts.User" user "User.Comments")
		(21 "Eco1.User" user "User.Eco1")
		(23 "Eco2.User" user "User.Eco2")
		(25 "Edge.Cuts" user "Board Geometry/Outline")
		(27 "Margin" user)
		(31 "F.CrtYd" user "Package Geometry/Place Bound Top")
		(29 "B.CrtYd" user "Package Geometry/Place Bound Bottom")
		(35 "F.Fab" user "Ref Des/Assembly Top")
		(33 "B.Fab" user "Ref Des/Assembly Bottom")
	)
	(footprint ""
		(layer "B.Cu")
		(at 482.512116 -142.485872 -90)
		(property "Reference" "R6W4"
			(at 0.8382 -0.67818 270)
			(unlocked yes)
			(layer "B.SilkS")
			(effects
				(font
					(size 0.4064 0.254)
					(thickness 0.1524)
				)
				(justify left mirror)
			)
		)
		(property "Value" ""
			(at 0 0 90)
			(layer "B.Fab")
			(effects
				(font
					(size 1.27 1.27)
				)
				(justify mirror)
			)
		)
		(duplicate_pad_numbers_are_jumpers no)
		(fp_poly
			(pts
				(xy 0.2794 -0.1016) (xy -0.2794 -0.1016) (xy -0.2794 0.9906) (xy 0.2794 0.9906)
			)
			(stroke
				(width 0)
				(type default)
			)
			(fill no)
			(layer "B.CrtYd")
		)
		(fp_line
			(start -0.2794 0.9906)
			(end -0.2794 -0.1016)
			(stroke
				(width 0.1)
				(type default)
			)
			(layer "B.Fab")
		)
		(fp_line
			(start 0.2794 0.9906)
			(end -0.2794 0.9906)
			(stroke
				(width 0.1)
				(type default)
			)
			(layer "B.Fab")
		)
		(fp_line
			(start -0.2794 -0.1016)
			(end 0.2794 -0.1016)
			(stroke
				(width 0.1)
				(type default)
			)
			(layer "B.Fab")
		)
		(fp_line
			(start 0.2794 -0.1016)
			(end 0.2794 0.9906)
			(stroke
				(width 0.1)
				(type default)
			)
			(layer "B.Fab")
		)
		(pad "1" smd rect
			(at 0 0 90)
			(size 0.508 0.508)
			(layers "B.Cu" "B.Mask" "B.Paste")
			(net "P3V3_STBY")
		)
		(pad "2" smd rect
			(at 0 0.889 90)
			(size 0.508 0.508)
			(layers "B.Cu" "B.Mask" "B.Paste")
			(net "PCA9555_A2")
		)
		(zone
			(layer "B.Cu")
			(hatch none 0.5)
			(connect_pads
				(clearance 0)
			)
			(min_thickness 0.25)
			(keepout
				(tracks not_allowed)
				(vias allowed)
				(pads allowed)
				(copperpour not_allowed)
				(footprints allowed)
			)
			(placement
				(enabled no)
				(sheetname "")
			)
			(fill
				(thermal_gap 0.5)
				(thermal_bridge_width 0.5)
				(island_removal_mode 0)
			)
			(polygon
				(pts
					(xy 481.877116 -142.231872) (xy 481.877116 -142.739872) (xy 482.258116 -142.739872) (xy 482.258116 -142.231872)
				)
			)
		)
		(zone
			(layer "B.Cu")
			(hatch none 0.5)
			(connect_pads
				(clearance 0)
			)
			(min_thickness 0.25)
			(keepout
				(tracks allowed)
				(vias not_allowed)
				(pads allowed)
				(copperpour not_allowed)
				(footprints allowed)
			)
			(placement
				(enabled no)
				(sheetname "")
			)
			(fill
				(thermal_gap 0.5)
				(thermal_bridge_width 0.5)
				(island_removal_mode 0)
			)
			(polygon
				(pts
					(xy 482.258116 -142.231872) (xy 482.258116 -142.739872) (xy 481.877116 -142.739872) (xy 481.877116 -142.231872)
				)
			)
		)
	)
	(footprint ""
		(layer "B.Cu")
		(at 418.719 -31.8135 180)
		(property "Reference" "C25W54"
			(at 0.8382 -0.67818 180)
			(unlocked yes)
			(layer "B.SilkS")
			(effects
				(font
					(size 0.4064 0.254)
					(thickness 0.1524)
				)
				(justify left mirror)
			)
		)
		(property "Value" ""
			(at 0 0 0)
			(layer "B.Fab")
			(effects
				(font
					(size 1.27 1.27)
				)
				(justify mirror)
			)
		)
		(duplicate_pad_numbers_are_jumpers no)
		(fp_poly
			(pts
				(xy -0.3048 -0.1016) (xy -0.3048 0.9906) (xy 0.3048 0.9906) (xy 0.3048 -0.1016)
			)
			(stroke
				(width 0)
				(type default)
			)
			(fill no)
			(layer "B.CrtYd")
		)
		(fp_line
			(start 0.3048 0.9906)
			(end -0.3048 0.9906)
			(stroke
				(width 0.1)
				(type default)
			)
			(layer "B.Fab")
		)
		(fp_line
			(start 0.3048 -0.1016)
			(end 0.3048 0.9906)
			(stroke
				(width 0.1)
				(type default)
			)
			(layer "B.Fab")
		)
		(fp_line
			(start -0.3048 0.9906)
			(end -0.3048 -0.1016)
			(stroke
				(width 0.1)
				(type default)
			)
			(layer "B.Fab")
		)
		(fp_line
			(start -0.3048 -0.1016)
			(end 0.3048 -0.1016)
			(stroke
				(width 0.1)
				(type default)
			)
			(layer "B.Fab")
		)
		(pad "1" smd rect
			(at 0 0)
			(size 0.508 0.508)
			(layers "B.Cu" "B.Mask" "B.Paste")
			(net "P1V2_AUX_BMC")
		)
		(pad "2" smd rect
			(at 0 0.889)
			(size 0.508 0.508)
			(layers "B.Cu" "B.Mask" "B.Paste")
			(net "GND")
		)
		(zone
			(layer "B.Cu")
			(hatch none 0.5)
			(connect_pads
				(clearance 0)
			)
			(min_thickness 0.25)
			(keepout
				(tracks not_allowed)
				(vias allowed)
				(pads allowed)
				(copperpour not_allowed)
				(footprints allowed)
			)
			(placement
				(enabled no)
				(sheetname "")
			)
			(fill
				(thermal_gap 0.5)
				(thermal_bridge_width 0.5)
				(island_removal_mode 0)
			)
			(polygon
				(pts
					(xy 418.465 -32.4485) (xy 418.973 -32.4485) (xy 418.973 -32.0675) (xy 418.465 -32.0675)
				)
			)
		)
		(zone
			(layer "B.Cu")
			(hatch none 0.5)
			(connect_pads
				(clearance 0)
			)
			(min_thickness 0.25)
			(keepout
				(tracks allowed)
				(vias not_allowed)
				(pads allowed)
				(copperpour not_allowed)
				(footprints allowed)
			)
			(placement
				(enabled no)
				(sheetname "")
			)
			(fill
				(thermal_gap 0.5)
				(thermal_bridge_width 0.5)
				(island_removal_mode 0)
			)
			(polygon
				(pts
					(xy 418.465 -32.0675) (xy 418.973 -32.0675) (xy 418.973 -32.4485) (xy 418.465 -32.4485)
				)
			)
		)
	)
	(footprint ""
		(layer "B.Cu")
		(at 394.208 -63.627 90)
		(property "Reference" "C2T8"
			(at 0 0 90)
			(layer "B.SilkS")
			(hide yes)
			(effects
				(font
					(size 1.27 1.27)
				)
				(justify mirror)
			)
		)
		(property "Value" ""
			(at 0 0 90)
			(layer "B.Fab")
			(effects
				(font
					(size 1.27 1.27)
				)
				(justify mirror)
			)
		)
		(duplicate_pad_numbers_are_jumpers no)
		(fp_poly
			(pts
				(xy -0.3048 -0.1016) (xy -0.3048 0.9906) (xy 0.3048 0.9906) (xy 0.3048 -0.1016)
			)
			(stroke
				(width 0)
				(type default)
			)
			(fill no)
			(layer "B.CrtYd")
		)
		(fp_line
			(start 0.3048 -0.1016)
			(end 0.3048 0.9906)
			(stroke
				(width 0.1)
				(type default)
			)
			(layer "B.Fab")
		)
		(fp_line
			(start -0.3048 -0.1016)
			(end 0.3048 -0.1016)
			(stroke
				(width 0.1)
				(type default)
			)
			(layer "B.Fab")
		)
		(fp_line
			(start 0.3048 0.9906)
			(end -0.3048 0.9906)
			(stroke
				(width 0.1)
				(type default)
			)
			(layer "B.Fab")
		)
		(fp_line
			(start -0.3048 0.9906)
			(end -0.3048 -0.1016)
			(stroke
				(width 0.1)
				(type default)
			)
			(layer "B.Fab")
		)
		(pad "1" smd rect
			(at 0 0 270)
			(size 0.508 0.508)
			(layers "B.Cu" "B.Mask" "B.Paste")
			(net "P3V3_STBY")
		)
		(pad "2" smd rect
			(at 0 0.889 270)
			(size 0.508 0.508)
			(layers "B.Cu" "B.Mask" "B.Paste")
			(net "GND")
		)
		(zone
			(layer "B.Cu")
			(hatch none 0.5)
			(connect_pads
				(clearance 0)
			)
			(min_thickness 0.25)
			(keepout
				(tracks allowed)
				(vias not_allowed)
				(pads allowed)
				(copperpour not_allowed)
				(footprints allowed)
			)
			(placement
				(enabled no)
				(sheetname "")
			)
			(fill
				(thermal_gap 0.5)
				(thermal_bridge_width 0.5)
				(island_removal_mode 0)
			)
			(polygon
				(pts
					(xy 394.462 -63.881) (xy 394.462 -63.373) (xy 394.843 -63.373) (xy 394.843 -63.881)
				)
			)
		)
		(zone
			(layer "B.Cu")
			(hatch none 0.5)
			(connect_pads
				(clearance 0)
			)
			(min_thickness 0.25)
			(keepout
				(tracks not_allowed)
				(vias allowed)
				(pads allowed)
				(copperpour not_allowed)
				(footprints allowed)
			)
			(placement
				(enabled no)
				(sheetname "")
			)
			(fill
				(thermal_gap 0.5)
				(thermal_bridge_width 0.5)
				(island_removal_mode 0)
			)
			(polygon
				(pts
					(xy 394.843 -63.881) (xy 394.843 -63.373) (xy 394.462 -63.373) (xy 394.462 -63.881)
				)
			)
		)
	)
)
